(kicad_pcb
	(version 20260206)
	(generator "pcbnew")
	(generator_version "10.0")
	(general
		(thickness 1.6)
		(legacy_teardrops no)
	)
	(paper "A4")
	(title_block
		(title "Wiwynn_Tioga_Pass_MB.brd")
		(comment 1 "Tioga Pass / footprints 2498-2505 of 4770")
	)
	(layers
		(0 "F.Cu" signal "TOP")
		(4 "In1.Cu" signal "L2GND")
		(6 "In2.Cu" signal "L3")
		(8 "In3.Cu" signal "L4GND")
		(10 "In4.Cu" signal "L5")
		(12 "In5.Cu" signal "L6GND")
		(14 "In6.Cu" signal "L7VCC")
		(16 "In7.Cu" signal "L8VCC")
		(18 "In8.Cu" signal "L9GND")
		(20 "In9.Cu" signal "L10")
		(22 "In10.Cu" signal "L11GND")
		(24 "In11.Cu" signal "L12")
		(26 "In12.Cu" signal "L13GND")
		(2 "B.Cu" signal "BOTTOM")
		(9 "F.Adhes" user "F.Adhesive")
		(11 "B.Adhes" user "B.Adhesive")
		(13 "F.Paste" user "Package Geometry/Pastemask Top")
		(15 "B.Paste" user "Package Geometry/Pastemask Bottom")
		(5 "F.SilkS" user "Ref Des/Silkscreen Top")
		(7 "B.SilkS" user "Ref Des/Silkscreen Bottom")
		(1 "F.Mask" user "Board Geometry/Soldermask Top")
		(3 "B.Mask" user "Board Geometry/Soldermask Bottom")
		(17 "Dwgs.User" user "User.Drawings")
		(19 "Cmts.User" user "User.Comments")
		(21 "Eco1.User" user "User.Eco1")
		(23 "Eco2.User" user "User.Eco2")
		(25 "Edge.Cuts" user "Board Geometry/Outline")
		(27 "Margin" user)
		(31 "F.CrtYd" user "Package Geometry/Place Bound Top")
		(29 "B.CrtYd" user "Package Geometry/Place Bound Bottom")
		(35 "F.Fab" user "Ref Des/Assembly Top")
		(33 "B.Fab" user "Ref Des/Assembly Bottom")
	)
	(footprint ""
		(layer "B.Cu")
		(at 346.8751 -156.5656 -90)
		(property "Reference" "C7A18"
			(at 0 0 90)
			(layer "B.SilkS")
			(hide yes)
			(effects
				(font
					(size 1.27 1.27)
				)
				(justify mirror)
			)
		)
		(property "Value" "*"
			(at -1.1811 -2.8194 270)
			(unlocked yes)
			(layer "B.Fab")
			(hide yes)
			(effects
				(font
					(size 1.27 1.016)
					(thickness 0.1524)
				)
				(justify mirror)
			)
		)
		(property "Device Type" "SC1U10V2KX-4-GP_SMD-BCG6-SC1U1A"
			(at -1.1811 -4.3434 270)
			(unlocked yes)
			(layer "B.Fab")
			(hide yes)
			(effects
				(font
					(size 1.27 1.016)
					(thickness 0.1524)
				)
				(justify mirror)
			)
		)
		(duplicate_pad_numbers_are_jumpers no)
		(fp_rect
			(start 0.4318 0.9525)
			(end -0.4318 -0.9525)
			(stroke
				(width 0)
				(type default)
			)
			(fill no)
			(layer "B.CrtYd")
		)
		(fp_rect
			(start 0.4318 0.9525)
			(end -0.4318 -0.9525)
			(stroke
				(width 0)
				(type default)
			)
			(fill no)
			(layer "B.Fab")
		)
		(pad "1" smd custom
			(at 0 -0.4445 90)
			(size 0.1524 0.1524)
			(layers "B.Cu" "B.Mask" "B.Paste")
			(net "P5V_STBY")
			(options
				(clearance outline)
				(anchor circle)
			)
			(primitives
				(gr_poly
					(pts
						(arc
							(start 0.3048 0.2032)
							(mid 0.275042 0.275042)
							(end 0.2032 0.3048)
						)
						(arc
							(start -0.2032 0.3048)
							(mid -0.275042 0.275042)
							(end -0.3048 0.2032)
						)
						(arc
							(start -0.3048 -0.2032)
							(mid -0.275042 -0.275042)
							(end -0.2032 -0.3048)
						)
						(arc
							(start 0.2032 -0.3048)
							(mid 0.275042 -0.275042)
							(end 0.3048 -0.2032)
						)
					)
					(width 0)
					(fill yes)
				)
			)
		)
		(pad "2" smd custom
			(at 0 0.4445 90)
			(size 0.1524 0.1524)
			(layers "B.Cu" "B.Mask" "B.Paste")
			(net "GND")
			(options
				(clearance outline)
				(anchor circle)
			)
			(primitives
				(gr_poly
					(pts
						(arc
							(start 0.3048 0.2032)
							(mid 0.275042 0.275042)
							(end 0.2032 0.3048)
						)
						(arc
							(start -0.2032 0.3048)
							(mid -0.275042 0.275042)
							(end -0.3048 0.2032)
						)
						(arc
							(start -0.3048 -0.2032)
							(mid -0.275042 -0.275042)
							(end -0.2032 -0.3048)
						)
						(arc
							(start 0.2032 -0.3048)
							(mid 0.275042 -0.275042)
							(end 0.3048 -0.2032)
						)
					)
					(width 0)
					(fill yes)
				)
			)
		)
	)
	(footprint ""
		(layer "B.Cu")
		(at 104.5591 -12.954 90)
		(property "Reference" "C5G94"
			(at -1.14681 0.76708 180)
			(unlocked yes)
			(layer "B.SilkS")
			(effects
				(font
					(size 0.7874 0.5842)
					(thickness 0.1524)
				)
				(justify mirror)
			)
		)
		(property "Value" ""
			(at 0 0 90)
			(layer "B.Fab")
			(effects
				(font
					(size 1.27 1.27)
				)
				(justify mirror)
			)
		)
		(duplicate_pad_numbers_are_jumpers no)
		(fp_rect
			(start -0.4953 -0.2032)
			(end 0.4953 1.6002)
			(stroke
				(width 0)
				(type default)
			)
			(fill no)
			(layer "B.CrtYd")
		)
		(fp_line
			(start 0.4953 -0.2032)
			(end -0.4953 -0.2032)
			(stroke
				(width 0.1)
				(type default)
			)
			(layer "B.Fab")
		)
		(fp_line
			(start -0.4953 -0.2032)
			(end -0.4953 1.6002)
			(stroke
				(width 0.1)
				(type default)
			)
			(layer "B.Fab")
		)
		(fp_line
			(start 0.4953 1.6002)
			(end 0.4953 -0.2032)
			(stroke
				(width 0.1)
				(type default)
			)
			(layer "B.Fab")
		)
		(fp_line
			(start -0.4953 1.6002)
			(end 0.4953 1.6002)
			(stroke
				(width 0.1)
				(type default)
			)
			(layer "B.Fab")
		)
		(pad "1" smd rect
			(at 0 0 270)
			(size 0.762 0.889)
			(layers "B.Cu" "B.Mask" "B.Paste")
			(net "PVDDQ_GHJ")
		)
		(pad "2" smd rect
			(at 0 1.397 270)
			(size 0.762 0.889)
			(layers "B.Cu" "B.Mask" "B.Paste")
			(net "GND")
		)
		(zone
			(layer "B.Cu")
			(hatch none 0.5)
			(connect_pads
				(clearance 0)
			)
			(min_thickness 0.25)
			(keepout
				(tracks not_allowed)
				(vias allowed)
				(pads allowed)
				(copperpour not_allowed)
				(footprints allowed)
			)
			(placement
				(enabled no)
				(sheetname "")
			)
			(fill
				(thermal_gap 0.5)
				(thermal_bridge_width 0.5)
				(island_removal_mode 0)
			)
			(polygon
				(pts
					(xy 105.0036 -12.573) (xy 105.5116 -12.573) (xy 105.5116 -13.335) (xy 105.0036 -13.335)
				)
			)
		)
	)
	(footprint ""
		(layer "B.Cu")
		(at 390.635744 -23.356316 -90)
		(property "Reference" "C2T24"
			(at 0 0 90)
			(layer "B.SilkS")
			(hide yes)
			(effects
				(font
					(size 1.27 1.27)
				)
				(justify mirror)
			)
		)
		(property "Value" ""
			(at 0 0 90)
			(layer "B.Fab")
			(effects
				(font
					(size 1.27 1.27)
				)
				(justify mirror)
			)
		)
		(duplicate_pad_numbers_are_jumpers no)
		(fp_poly
			(pts
				(xy -0.3048 -0.1016) (xy -0.3048 0.9906) (xy 0.3048 0.9906) (xy 0.3048 -0.1016)
			)
			(stroke
				(width 0)
				(type default)
			)
			(fill no)
			(layer "B.CrtYd")
		)
		(fp_line
			(start -0.3048 0.9906)
			(end -0.3048 -0.1016)
			(stroke
				(width 0.1)
				(type default)
			)
			(layer "B.Fab")
		)
		(fp_line
			(start 0.3048 0.9906)
			(end -0.3048 0.9906)
			(stroke
				(width 0.1)
				(type default)
			)
			(layer "B.Fab")
		)
		(fp_line
			(start -0.3048 -0.1016)
			(end 0.3048 -0.1016)
			(stroke
				(width 0.1)
				(type default)
			)
			(layer "B.Fab")
		)
		(fp_line
			(start 0.3048 -0.1016)
			(end 0.3048 0.9906)
			(stroke
				(width 0.1)
				(type default)
			)
			(layer "B.Fab")
		)
		(pad "1" smd rect
			(at 0 0 90)
			(size 0.508 0.508)
			(layers "B.Cu" "B.Mask" "B.Paste")
			(net "P3V3")
		)
		(pad "2" smd rect
			(at 0 0.889 90)
			(size 0.508 0.508)
			(layers "B.Cu" "B.Mask" "B.Paste")
			(net "GND")
		)
		(zone
			(layer "B.Cu")
			(hatch none 0.5)
			(connect_pads
				(clearance 0)
			)
			(min_thickness 0.25)
			(keepout
				(tracks not_allowed)
				(vias allowed)
				(pads allowed)
				(copperpour not_allowed)
				(footprints allowed)
			)
			(placement
				(enabled no)
				(sheetname "")
			)
			(fill
				(thermal_gap 0.5)
				(thermal_bridge_width 0.5)
				(island_removal_mode 0)
			)
			(polygon
				(pts
					(xy 390.000744 -23.102316) (xy 390.000744 -23.610316) (xy 390.381744 -23.610316) (xy 390.381744 -23.102316)
				)
			)
		)
		(zone
			(layer "B.Cu")
			(hatch none 0.5)
			(connect_pads
				(clearance 0)
			)
			(min_thickness 0.25)
			(keepout
				(tracks allowed)
				(vias not_allowed)
				(pads allowed)
				(copperpour not_allowed)
				(footprints allowed)
			)
			(placement
				(enabled no)
				(sheetname "")
			)
			(fill
				(thermal_gap 0.5)
				(thermal_bridge_width 0.5)
				(island_removal_mode 0)
			)
			(polygon
				(pts
					(xy 390.381744 -23.102316) (xy 390.381744 -23.610316) (xy 390.000744 -23.610316) (xy 390.000744 -23.102316)
				)
			)
		)
	)
	(footprint ""
		(layer "B.Cu")
		(at 450.215 -147.0406 -90)
		(property "Reference" "R25W166"
			(at 0.8382 -0.67818 270)
			(unlocked yes)
			(layer "B.SilkS")
			(effects
				(font
					(size 0.4064 0.254)
					(thickness 0.1524)
				)
				(justify left mirror)
			)
		)
		(property "Value" ""
			(at 0 0 90)
			(layer "B.Fab")
			(effects
				(font
					(size 1.27 1.27)
				)
				(justify mirror)
			)
		)
		(duplicate_pad_numbers_are_jumpers no)
		(fp_poly
			(pts
				(xy 0.2794 -0.1016) (xy -0.2794 -0.1016) (xy -0.2794 0.9906) (xy 0.2794 0.9906)
			)
			(stroke
				(width 0)
				(type default)
			)
			(fill no)
			(layer "B.CrtYd")
		)
		(fp_line
			(start -0.2794 0.9906)
			(end -0.2794 -0.1016)
			(stroke
				(width 0.1)
				(type default)
			)
			(layer "B.Fab")
		)
		(fp_line
			(start 0.2794 0.9906)
			(end -0.2794 0.9906)
			(stroke
				(width 0.1)
				(type default)
			)
			(layer "B.Fab")
		)
		(fp_line
			(start -0.2794 -0.1016)
			(end 0.2794 -0.1016)
			(stroke
				(width 0.1)
				(type default)
			)
			(layer "B.Fab")
		)
		(fp_line
			(start 0.2794 -0.1016)
			(end 0.2794 0.9906)
			(stroke
				(width 0.1)
				(type default)
			)
			(layer "B.Fab")
		)
		(pad "1" smd rect
			(at 0 0 90)
			(size 0.508 0.508)
			(layers "B.Cu" "B.Mask" "B.Paste")
			(net "PD_GTL2014_DIR_6")
		)
		(pad "2" smd rect
			(at 0 0.889 90)
			(size 0.508 0.508)
			(layers "B.Cu" "B.Mask" "B.Paste")
			(net "GND")
		)
		(zone
			(layer "B.Cu")
			(hatch none 0.5)
			(connect_pads
				(clearance 0)
			)
			(min_thickness 0.25)
			(keepout
				(tracks not_allowed)
				(vias allowed)
				(pads allowed)
				(copperpour not_allowed)
				(footprints allowed)
			)
			(placement
				(enabled no)
				(sheetname "")
			)
			(fill
				(thermal_gap 0.5)
				(thermal_bridge_width 0.5)
				(island_removal_mode 0)
			)
			(polygon
				(pts
					(xy 449.58 -146.7866) (xy 449.58 -147.2946) (xy 449.961 -147.2946) (xy 449.961 -146.7866)
				)
			)
		)
		(zone
			(layer "B.Cu")
			(hatch none 0.5)
			(connect_pads
				(clearance 0)
			)
			(min_thickness 0.25)
			(keepout
				(tracks allowed)
				(vias not_allowed)
				(pads allowed)
				(copperpour not_allowed)
				(footprints allowed)
			)
			(placement
				(enabled no)
				(sheetname "")
			)
			(fill
				(thermal_gap 0.5)
				(thermal_bridge_width 0.5)
				(island_removal_mode 0)
			)
			(polygon
				(pts
					(xy 449.961 -146.7866) (xy 449.961 -147.2946) (xy 449.58 -147.2946) (xy 449.58 -146.7866)
				)
			)
		)
	)
	(footprint ""
		(layer "B.Cu")
		(at 389.0518 -125.507242 90)
		(property "Reference" "R3M11"
			(at 0 0 90)
			(layer "B.SilkS")
			(hide yes)
			(effects
				(font
					(size 1.27 1.27)
				)
				(justify mirror)
			)
		)
		(property "Value" ""
			(at 0 0 90)
			(layer "B.Fab")
			(effects
				(font
					(size 1.27 1.27)
				)
				(justify mirror)
			)
		)
		(duplicate_pad_numbers_are_jumpers no)
		(fp_poly
			(pts
				(xy 0.2794 -0.1016) (xy -0.2794 -0.1016) (xy -0.2794 0.9906) (xy 0.2794 0.9906)
			)
			(stroke
				(width 0)
				(type default)
			)
			(fill no)
			(layer "B.CrtYd")
		)
		(fp_line
			(start 0.2794 -0.1016)
			(end 0.2794 0.9906)
			(stroke
				(width 0.1)
				(type default)
			)
			(layer "B.Fab")
		)
		(fp_line
			(start -0.2794 -0.1016)
			(end 0.2794 -0.1016)
			(stroke
				(width 0.1)
				(type default)
			)
			(layer "B.Fab")
		)
		(fp_line
			(start 0.2794 0.9906)
			(end -0.2794 0.9906)
			(stroke
				(width 0.1)
				(type default)
			)
			(layer "B.Fab")
		)
		(fp_line
			(start -0.2794 0.9906)
			(end -0.2794 -0.1016)
			(stroke
				(width 0.1)
				(type default)
			)
			(layer "B.Fab")
		)
		(pad "1" smd rect
			(at 0 0 270)
			(size 0.508 0.508)
			(layers "B.Cu" "B.Mask" "B.Paste")
			(net "A_PCIE_RCOMP_P")
		)
		(pad "2" smd rect
			(at 0 0.889 270)
			(size 0.508 0.508)
			(layers "B.Cu" "B.Mask" "B.Paste")
			(net "A_PCIE_RCOMP_N")
		)
		(zone
			(layer "B.Cu")
			(hatch none 0.5)
			(connect_pads
				(clearance 0)
			)
			(min_thickness 0.25)
			(keepout
				(tracks allowed)
				(vias not_allowed)
				(pads allowed)
				(copperpour not_allowed)
				(footprints allowed)
			)
			(placement
				(enabled no)
				(sheetname "")
			)
			(fill
				(thermal_gap 0.5)
				(thermal_bridge_width 0.5)
				(island_removal_mode 0)
			)
			(polygon
				(pts
					(xy 389.3058 -125.761242) (xy 389.3058 -125.253242) (xy 389.6868 -125.253242) (xy 389.6868 -125.761242)
				)
			)
		)
		(zone
			(layer "B.Cu")
			(hatch none 0.5)
			(connect_pads
				(clearance 0)
			)
			(min_thickness 0.25)
			(keepout
				(tracks not_allowed)
				(vias allowed)
				(pads allowed)
				(copperpour not_allowed)
				(footprints allowed)
			)
			(placement
				(enabled no)
				(sheetname "")
			)
			(fill
				(thermal_gap 0.5)
				(thermal_bridge_width 0.5)
				(island_removal_mode 0)
			)
			(polygon
				(pts
					(xy 389.6868 -125.761242) (xy 389.6868 -125.253242) (xy 389.3058 -125.253242) (xy 389.3058 -125.761242)
				)
			)
		)
	)
	(footprint ""
		(layer "B.Cu")
		(at 411.861 -23.0632 90)
		(property "Reference" "FB2T3"
			(at 0 0 90)
			(layer "B.SilkS")
			(hide yes)
			(effects
				(font
					(size 1.27 1.27)
				)
				(justify mirror)
			)
		)
		(property "Value" "*"
			(at -0.0254 -2.8829 90)
			(unlocked yes)
			(layer "B.Fab")
			(hide yes)
			(effects
				(font
					(size 1.27 1.016)
					(thickness 0.1524)
				)
				(justify mirror)
			)
		)
		(property "Device Type" "HCB1608KF-800T30-GP_DISCRET-G9A"
			(at -0.0254 -4.4069 90)
			(unlocked yes)
			(layer "B.Fab")
			(hide yes)
			(effects
				(font
					(size 1.27 1.016)
					(thickness 0.1524)
				)
				(justify mirror)
			)
		)
		(duplicate_pad_numbers_are_jumpers no)
		(fp_line
			(start -0.254 0)
			(end 0.254 0)
			(stroke
				(width 0.2032)
				(type default)
			)
			(layer "B.SilkS")
		)
		(fp_rect
			(start 0.5842 1.3335)
			(end -0.5842 -1.3335)
			(stroke
				(width 0)
				(type default)
			)
			(fill no)
			(layer "B.CrtYd")
		)
		(fp_rect
			(start 0.5842 1.3335)
			(end -0.5842 -1.3335)
			(stroke
				(width 0)
				(type default)
			)
			(fill no)
			(layer "B.Fab")
		)
		(pad "1" smd custom
			(at 0 -0.762 270)
			(size 0.2159 0.2159)
			(layers "B.Cu" "B.Mask" "B.Paste")
			(net "P3V3_STBY")
			(options
				(clearance outline)
				(anchor circle)
			)
			(primitives
				(gr_poly
					(pts
						(arc
							(start -0.3302 0.4318)
							(mid -0.402042 0.402042)
							(end -0.4318 0.3302)
						)
						(arc
							(start -0.4318 -0.3302)
							(mid -0.402042 -0.402042)
							(end -0.3302 -0.4318)
						)
						(arc
							(start 0.3302 -0.4318)
							(mid 0.402042 -0.402042)
							(end 0.4318 -0.3302)
						)
						(arc
							(start 0.4318 0.3302)
							(mid 0.402042 0.402042)
							(end 0.3302 0.4318)
						)
					)
					(width 0)
					(fill yes)
				)
			)
		)
		(pad "2" smd custom
			(at 0 0.762 270)
			(size 0.2159 0.2159)
			(layers "B.Cu" "B.Mask" "B.Paste")
			(net "VCC_ADCAV3V3")
			(options
				(clearance outline)
				(anchor circle)
			)
			(primitives
				(gr_poly
					(pts
						(arc
							(start -0.3302 0.4318)
							(mid -0.402042 0.402042)
							(end -0.4318 0.3302)
						)
						(arc
							(start -0.4318 -0.3302)
							(mid -0.402042 -0.402042)
							(end -0.3302 -0.4318)
						)
						(arc
							(start 0.3302 -0.4318)
							(mid 0.402042 -0.402042)
							(end 0.4318 -0.3302)
						)
						(arc
							(start 0.4318 0.3302)
							(mid 0.402042 0.402042)
							(end 0.3302 0.4318)
						)
					)
					(width 0)
					(fill yes)
				)
			)
		)
	)
	(footprint ""
		(layer "B.Cu")
		(at 184.421272 -9.119108 90)
		(property "Reference" "C22W6"
			(at 0 0 90)
			(layer "B.SilkS")
			(hide yes)
			(effects
				(font
					(size 1.27 1.27)
				)
				(justify mirror)
			)
		)
		(property "Value" "*"
			(at 0.0762 -6.2357 90)
			(unlocked yes)
			(layer "B.Fab")
			(hide yes)
			(effects
				(font
					(size 1.27 1.016)
					(thickness 0.1524)
				)
				(justify mirror)
			)
		)
		(property "Device Type" "SC22U16V5MX-4-GP_SMD-BCG5-SC22A"
			(at 0.0762 -8.2677 90)
			(unlocked yes)
			(layer "B.Fab")
			(hide yes)
			(effects
				(font
					(size 1.27 1.016)
					(thickness 0.1524)
				)
				(justify mirror)
			)
		)
		(duplicate_pad_numbers_are_jumpers no)
		(fp_line
			(start -0.635 0)
			(end 0.635 0)
			(stroke
				(width 0.508)
				(type default)
			)
			(layer "B.SilkS")
		)
		(fp_rect
			(start 0.9652 1.778)
			(end -0.9652 -1.778)
			(stroke
				(width 0)
				(type default)
			)
			(fill no)
			(layer "B.CrtYd")
		)
		(fp_poly
			(pts
				(xy 0.9652 -1.778) (xy -0.9652 -1.778) (xy -0.9652 1.778) (xy 0.9652 1.778)
			)
			(stroke
				(width 0)
				(type default)
			)
			(fill no)
			(layer "B.Fab")
		)
		(pad "1" smd rect
			(at 0 -0.9652 270)
			(size 1.397 1.143)
			(layers "B.Cu" "B.Mask" "B.Paste")
			(net "VR_FET_SW_P12V_STBY_PVPP_GHJ")
		)
		(pad "2" smd rect
			(at 0 0.9652 270)
			(size 1.397 1.143)
			(layers "B.Cu" "B.Mask" "B.Paste")
			(net "GND")
		)
	)
	(footprint ""
		(layer "B.Cu")
		(at 342.642952 -89.300558 180)
		(property "Reference" "C3N39"
			(at 0 0 0)
			(layer "B.SilkS")
			(hide yes)
			(effects
				(font
					(size 1.27 1.27)
				)
				(justify mirror)
			)
		)
		(property "Value" ""
			(at 0 0 0)
			(layer "B.Fab")
			(effects
				(font
					(size 1.27 1.27)
				)
				(justify mirror)
			)
		)
		(duplicate_pad_numbers_are_jumpers no)
		(fp_poly
			(pts
				(xy -0.3048 -0.1016) (xy -0.3048 0.9906) (xy 0.3048 0.9906) (xy 0.3048 -0.1016)
			)
			(stroke
				(width 0)
				(type default)
			)
			(fill no)
			(layer "B.CrtYd")
		)
		(fp_line
			(start 0.3048 0.9906)
			(end -0.3048 0.9906)
			(stroke
				(width 0.1)
				(type default)
			)
			(layer "B.Fab")
		)
		(fp_line
			(start 0.3048 -0.1016)
			(end 0.3048 0.9906)
			(stroke
				(width 0.1)
				(type default)
			)
			(layer "B.Fab")
		)
		(fp_line
			(start -0.3048 0.9906)
			(end -0.3048 -0.1016)
			(stroke
				(width 0.1)
				(type default)
			)
			(layer "B.Fab")
		)
		(fp_line
			(start -0.3048 -0.1016)
			(end 0.3048 -0.1016)
			(stroke
				(width 0.1)
				(type default)
			)
			(layer "B.Fab")
		)
		(pad "1" smd rect
			(at 0 0)
			(size 0.508 0.508)
			(layers "B.Cu" "B.Mask" "B.Paste")
			(net "VR_PVCCIO_CPU0_AVSP")
		)
		(pad "2" smd rect
			(at 0 0.889)
			(size 0.508 0.508)
			(layers "B.Cu" "B.Mask" "B.Paste")
			(net "VSENSE_PVCCIO_CPU0_AVSN")
		)
		(zone
			(layer "B.Cu")
			(hatch none 0.5)
			(connect_pads
				(clearance 0)
			)
			(min_thickness 0.25)
			(keepout
				(tracks not_allowed)
				(vias allowed)
				(pads allowed)
				(copperpour not_allowed)
				(footprints allowed)
			)
			(placement
				(enabled no)
				(sheetname "")
			)
			(fill
				(thermal_gap 0.5)
				(thermal_bridge_width 0.5)
				(island_removal_mode 0)
			)
			(polygon
				(pts
					(xy 342.388952 -89.935558) (xy 342.896952 -89.935558) (xy 342.896952 -89.554558) (xy 342.388952 -89.554558)
				)
			)
		)
		(zone
			(layer "B.Cu")
			(hatch none 0.5)
			(connect_pads
				(clearance 0)
			)
			(min_thickness 0.25)
			(keepout
				(tracks allowed)
				(vias not_allowed)
				(pads allowed)
				(copperpour not_allowed)
				(footprints allowed)
			)
			(placement
				(enabled no)
				(sheetname "")
			)
			(fill
				(thermal_gap 0.5)
				(thermal_bridge_width 0.5)
				(island_removal_mode 0)
			)
			(polygon
				(pts
					(xy 342.388952 -89.554558) (xy 342.896952 -89.554558) (xy 342.896952 -89.935558) (xy 342.388952 -89.935558)
				)
			)
		)
	)
)
